(kicad_pcb
	(version 20260206)
	(generator "pcbnew")
	(generator_version "10.0")
	(general
		(thickness 1.6)
		(legacy_teardrops no)
	)
	(paper "A4")
	(title_block
		(title "v1-chassis-manager — T6M_CM_d_v01_1031_1645.brd")
		(comment 1 "Open CloudServer (Microsoft) / footprints 925-933 of 2512")
	)
	(layers
		(0 "F.Cu" signal "TOP")
		(4 "In1.Cu" signal "GND1")
		(6 "In2.Cu" signal "IN1")
		(8 "In3.Cu" signal "VCC1")
		(10 "In4.Cu" signal "VCC2")
		(12 "In5.Cu" signal "GND2")
		(14 "In6.Cu" signal "IN2")
		(16 "In7.Cu" signal "IN3")
		(18 "In8.Cu" signal "GND3")
		(2 "B.Cu" signal "BOTTOM")
		(9 "F.Adhes" user "F.Adhesive")
		(11 "B.Adhes" user "B.Adhesive")
		(13 "F.Paste" user "Package Geometry/Pastemask Top")
		(15 "B.Paste" user "Package Geometry/Pastemask Bottom")
		(5 "F.SilkS" user "Ref Des/Silkscreen Top")
		(7 "B.SilkS" user "Ref Des/Silkscreen Bottom")
		(1 "F.Mask" user "Board Geometry/Soldermask Top")
		(3 "B.Mask" user "Board Geometry/Soldermask Bottom")
		(17 "Dwgs.User" user "User.Drawings")
		(19 "Cmts.User" user "User.Comments")
		(21 "Eco1.User" user "User.Eco1")
		(23 "Eco2.User" user "User.Eco2")
		(25 "Edge.Cuts" user "Board Geometry/Outline")
		(27 "Margin" user)
		(31 "F.CrtYd" user "Package Geometry/Place Bound Top")
		(29 "B.CrtYd" user "Package Geometry/Place Bound Bottom")
		(35 "F.Fab" user "Ref Des/Assembly Top")
		(33 "B.Fab" user "Ref Des/Assembly Bottom")
	)
	(footprint ""
		(layer "F.Cu")
		(at 128.029208 -51.745134 90)
		(property "Reference" "R616"
			(at 15.971266 30.925262 90)
			(unlocked yes)
			(layer "F.SilkS")
			(effects
				(font
					(size 0.7874 0.5842)
					(thickness 0.1524)
				)
				(justify left)
			)
		)
		(property "Value" ""
			(at 0 0 90)
			(layer "F.Fab")
			(effects
				(font
					(size 1.27 1.27)
				)
			)
		)
		(duplicate_pad_numbers_are_jumpers no)
		(fp_line
			(start 0.7874 -0.4064)
			(end 0.7874 0.4064)
			(stroke
				(width 0.1524)
				(type default)
			)
			(layer "F.SilkS")
		)
		(fp_line
			(start -0.7874 -0.4064)
			(end 0.7874 -0.4064)
			(stroke
				(width 0.1524)
				(type default)
			)
			(layer "F.SilkS")
		)
		(fp_line
			(start 0.7874 0.4064)
			(end -0.7874 0.4064)
			(stroke
				(width 0.1524)
				(type default)
			)
			(layer "F.SilkS")
		)
		(fp_line
			(start -0.7874 0.4064)
			(end -0.7874 -0.4064)
			(stroke
				(width 0.1524)
				(type default)
			)
			(layer "F.SilkS")
		)
		(fp_poly
			(pts
				(xy -0.508 0.2794) (xy -0.508 0.2286) (xy -0.635 0.2286) (xy -0.635 -0.254) (xy -0.5334 -0.254)
				(xy -0.5334 -0.2794) (xy 0.5334 -0.2794) (xy 0.5334 -0.254) (xy 0.635 -0.254) (xy 0.635 0.254) (xy 0.5334 0.254)
				(xy 0.5334 0.2794)
			)
			(stroke
				(width 0)
				(type default)
			)
			(fill no)
			(layer "F.CrtYd")
		)
		(pad "1" smd rect
			(at 0.40005 0 90)
			(size 0.4572 0.508)
			(layers "F.Cu" "F.Mask" "F.Paste")
			(net "P3V3_NODE1")
		)
		(pad "2" smd rect
			(at -0.40005 0 90)
			(size 0.4572 0.508)
			(layers "F.Cu" "F.Mask" "F.Paste")
			(net "UART_CTS_P5_N")
		)
	)
	(footprint ""
		(layer "F.Cu")
		(at 94.451932 -178.370992)
		(property "Reference" "R752"
			(at 86.67369 74.174096 0)
			(unlocked yes)
			(layer "F.SilkS")
			(effects
				(font
					(size 0.7874 0.5842)
					(thickness 0.1524)
				)
				(justify left)
			)
		)
		(property "Value" ""
			(at 0 0 0)
			(layer "F.Fab")
			(effects
				(font
					(size 1.27 1.27)
				)
			)
		)
		(duplicate_pad_numbers_are_jumpers no)
		(fp_line
			(start -0.7874 -0.4064)
			(end 0.7874 -0.4064)
			(stroke
				(width 0.1524)
				(type default)
			)
			(layer "F.SilkS")
		)
		(fp_line
			(start -0.7874 0.4064)
			(end -0.7874 -0.4064)
			(stroke
				(width 0.1524)
				(type default)
			)
			(layer "F.SilkS")
		)
		(fp_line
			(start 0.7874 -0.4064)
			(end 0.7874 0.4064)
			(stroke
				(width 0.1524)
				(type default)
			)
			(layer "F.SilkS")
		)
		(fp_line
			(start 0.7874 0.4064)
			(end -0.7874 0.4064)
			(stroke
				(width 0.1524)
				(type default)
			)
			(layer "F.SilkS")
		)
		(fp_poly
			(pts
				(xy -0.508 0.2794) (xy -0.508 0.2286) (xy -0.635 0.2286) (xy -0.635 -0.254) (xy -0.5334 -0.254)
				(xy -0.5334 -0.2794) (xy 0.5334 -0.2794) (xy 0.5334 -0.254) (xy 0.635 -0.254) (xy 0.635 0.254) (xy 0.5334 0.254)
				(xy 0.5334 0.2794)
			)
			(stroke
				(width 0)
				(type default)
			)
			(fill no)
			(layer "F.CrtYd")
		)
		(pad "1" smd rect
			(at 0.40005 0)
			(size 0.4572 0.508)
			(layers "F.Cu" "F.Mask" "F.Paste")
			(net "N21700941")
		)
		(pad "2" smd rect
			(at -0.40005 0)
			(size 0.4572 0.508)
			(layers "F.Cu" "F.Mask" "F.Paste")
			(net "GND")
		)
	)
	(footprint ""
		(layer "F.Cu")
		(at 150.073868 -39.972996 90)
		(property "Reference" "R1005"
			(at -1.681226 10.212832 90)
			(unlocked yes)
			(layer "F.SilkS")
			(effects
				(font
					(size 0.7874 0.5842)
					(thickness 0.1524)
				)
				(justify left)
			)
		)
		(property "Value" ""
			(at 0 0 90)
			(layer "F.Fab")
			(effects
				(font
					(size 1.27 1.27)
				)
			)
		)
		(duplicate_pad_numbers_are_jumpers no)
		(fp_line
			(start 0.7874 -0.4064)
			(end 0.7874 0.4064)
			(stroke
				(width 0.1524)
				(type default)
			)
			(layer "F.SilkS")
		)
		(fp_line
			(start -0.7874 -0.4064)
			(end 0.7874 -0.4064)
			(stroke
				(width 0.1524)
				(type default)
			)
			(layer "F.SilkS")
		)
		(fp_line
			(start 0.7874 0.4064)
			(end -0.7874 0.4064)
			(stroke
				(width 0.1524)
				(type default)
			)
			(layer "F.SilkS")
		)
		(fp_line
			(start -0.7874 0.4064)
			(end -0.7874 -0.4064)
			(stroke
				(width 0.1524)
				(type default)
			)
			(layer "F.SilkS")
		)
		(fp_poly
			(pts
				(xy -0.508 0.2794) (xy -0.508 0.2286) (xy -0.635 0.2286) (xy -0.635 -0.254) (xy -0.5334 -0.254)
				(xy -0.5334 -0.2794) (xy 0.5334 -0.2794) (xy 0.5334 -0.254) (xy 0.635 -0.254) (xy 0.635 0.254) (xy 0.5334 0.254)
				(xy 0.5334 0.2794)
			)
			(stroke
				(width 0)
				(type default)
			)
			(fill no)
			(layer "F.CrtYd")
		)
		(pad "1" smd rect
			(at 0.40005 0 90)
			(size 0.4572 0.508)
			(layers "F.Cu" "F.Mask" "F.Paste")
			(net "P5V_NODE1")
		)
		(pad "2" smd rect
			(at -0.40005 0 90)
			(size 0.4572 0.508)
			(layers "F.Cu" "F.Mask" "F.Paste")
			(net "UART_DTR_P1_N")
		)
	)
	(footprint ""
		(layer "F.Cu")
		(at 71.10476 -185.205624 90)
		(property "Reference" "C713"
			(at 4.006088 -0.94488 90)
			(unlocked yes)
			(layer "F.SilkS")
			(effects
				(font
					(size 0.7874 0.5842)
					(thickness 0.1524)
				)
				(justify left)
			)
		)
		(property "Value" ""
			(at 0 0 90)
			(layer "F.Fab")
			(effects
				(font
					(size 1.27 1.27)
				)
			)
		)
		(duplicate_pad_numbers_are_jumpers no)
		(fp_line
			(start 0.7874 -0.4064)
			(end 0.7874 0.4064)
			(stroke
				(width 0.1524)
				(type default)
			)
			(layer "F.SilkS")
		)
		(fp_line
			(start -0.7874 -0.4064)
			(end 0.7874 -0.4064)
			(stroke
				(width 0.1524)
				(type default)
			)
			(layer "F.SilkS")
		)
		(fp_line
			(start 0 0.381)
			(end 0 -0.381)
			(stroke
				(width 0.1524)
				(type default)
			)
			(layer "F.SilkS")
		)
		(fp_line
			(start 0.7874 0.4064)
			(end -0.7874 0.4064)
			(stroke
				(width 0.1524)
				(type default)
			)
			(layer "F.SilkS")
		)
		(fp_line
			(start -0.7874 0.4064)
			(end -0.7874 -0.4064)
			(stroke
				(width 0.1524)
				(type default)
			)
			(layer "F.SilkS")
		)
		(fp_poly
			(pts
				(xy -0.5334 0.254) (xy -0.635 0.254) (xy -0.635 0.2286) (xy -0.635 -0.254) (xy -0.5334 -0.254) (xy -0.5334 -0.2794)
				(xy 0.5334 -0.2794) (xy 0.5334 -0.254) (xy 0.635 -0.254) (xy 0.635 0.254) (xy 0.5334 0.254) (xy 0.5334 0.2794)
				(xy -0.508 0.2794) (xy -0.5334 0.2794)
			)
			(stroke
				(width 0)
				(type default)
			)
			(fill no)
			(layer "F.CrtYd")
		)
		(pad "1" smd rect
			(at 0.40005 0 90)
			(size 0.4572 0.508)
			(layers "F.Cu" "F.Mask" "F.Paste")
			(net "UART_T4_NODE4_RXD")
		)
		(pad "2" smd rect
			(at -0.40005 0 90)
			(size 0.4572 0.508)
			(layers "F.Cu" "F.Mask" "F.Paste")
			(net "GND")
		)
	)
	(footprint ""
		(layer "F.Cu")
		(at 62.035182 -173.527466 180)
		(property "Reference" "U88"
			(at 10.67943 -133.039612 90)
			(unlocked yes)
			(layer "F.SilkS")
			(effects
				(font
					(size 0.7874 0.5842)
					(thickness 0.1524)
				)
				(justify left)
			)
		)
		(property "Value" ""
			(at 0 0 180)
			(layer "F.Fab")
			(effects
				(font
					(size 1.27 1.27)
				)
			)
		)
		(duplicate_pad_numbers_are_jumpers no)
		(fp_line
			(start 1.549908 2.032)
			(end -1.549908 2.032)
			(stroke
				(width 0.1524)
				(type default)
			)
			(layer "F.SilkS")
		)
		(fp_line
			(start 1.549908 -2.032)
			(end 1.549908 2.032)
			(stroke
				(width 0.1524)
				(type default)
			)
			(layer "F.SilkS")
		)
		(fp_line
			(start -1.549908 2.032)
			(end -1.549908 -2.032)
			(stroke
				(width 0.1524)
				(type default)
			)
			(layer "F.SilkS")
		)
		(fp_line
			(start -1.549908 -2.032)
			(end 1.549908 -2.032)
			(stroke
				(width 0.1524)
				(type default)
			)
			(layer "F.SilkS")
		)
		(fp_poly
			(pts
				(xy -2.9464 1.016) (xy -2.9464 1.524) (xy -2.1844 1.27)
			)
			(stroke
				(width 0)
				(type default)
			)
			(fill yes)
			(layer "F.SilkS")
		)
		(fp_poly
			(pts
				(xy -1.549908 0.849884) (xy -1.2319 0.849884) (xy -1.2319 1.9431) (xy -1.1811 1.9431) (xy 1.1811 1.9431)
				(xy 1.2319 1.9431) (xy 1.2319 0.849884) (xy 1.549908 0.849884) (xy 1.549908 -0.849884) (xy 1.2319 -0.849884)
				(xy 1.2319 -1.9431) (xy 1.1811 -1.9431) (xy -1.1811 -1.9431) (xy -1.2319 -1.9431) (xy -1.2319 -0.849884)
				(xy -1.549908 -0.849884)
			)
			(stroke
				(width 0)
				(type default)
			)
			(fill no)
			(layer "F.CrtYd")
		)
		(fp_line
			(start 1.549908 0.849884)
			(end 1.549908 -0.849884)
			(stroke
				(width 0.1)
				(type default)
			)
			(layer "F.Fab")
		)
		(fp_line
			(start 1.549908 -0.849884)
			(end -1.549908 -0.849884)
			(stroke
				(width 0.1)
				(type default)
			)
			(layer "F.Fab")
		)
		(fp_line
			(start -1.549908 0.849884)
			(end 1.549908 0.849884)
			(stroke
				(width 0.1)
				(type default)
			)
			(layer "F.Fab")
		)
		(fp_line
			(start -1.549908 -0.849884)
			(end -1.549908 0.849884)
			(stroke
				(width 0.1)
				(type default)
			)
			(layer "F.Fab")
		)
		(fp_text user "3"
			(at 1.553972 2.531618 0)
			(unlocked yes)
			(layer "F.SilkS")
			(effects
				(font
					(size 0.635 0.4064)
					(thickness 0.1524)
				)
				(justify left)
			)
		)
		(fp_text user "4"
			(at 0.724916 -2.537968 0)
			(unlocked yes)
			(layer "F.SilkS")
			(effects
				(font
					(size 0.635 0.4064)
					(thickness 0.1524)
				)
				(justify left)
			)
		)
		(fp_text user "1"
			(at -1.126744 2.531618 0)
			(unlocked yes)
			(layer "F.SilkS")
			(effects
				(font
					(size 0.635 0.4064)
					(thickness 0.1524)
				)
				(justify left)
			)
		)
		(fp_text user "5"
			(at -1.872996 -2.637028 0)
			(unlocked yes)
			(layer "F.SilkS")
			(effects
				(font
					(size 0.635 0.4064)
					(thickness 0.1524)
				)
				(justify left)
			)
		)
		(pad "1" smd rect
			(at -0.94996 1.225042 180)
			(size 0.4572 1.3208)
			(layers "F.Cu" "F.Mask" "F.Paste")
			(net "Net_1709")
		)
		(pad "2" smd rect
			(at 0 1.225042 180)
			(size 0.4572 1.3208)
			(layers "F.Cu" "F.Mask" "F.Paste")
			(net "PSU2_DC_OK_R_BUF")
		)
		(pad "3" smd rect
			(at 0.94996 1.225042 180)
			(size 0.4572 1.3208)
			(layers "F.Cu" "F.Mask" "F.Paste")
			(net "GND")
		)
		(pad "4" smd rect
			(at 0.94996 -1.225042 180)
			(size 0.4572 1.3208)
			(layers "F.Cu" "F.Mask" "F.Paste")
			(net "PSU2_DC_OK")
		)
		(pad "5" smd rect
			(at -0.94996 -1.225042 180)
			(size 0.4572 1.3208)
			(layers "F.Cu" "F.Mask" "F.Paste")
			(net "P3V3_NODE1")
		)
	)
	(footprint ""
		(layer "F.Cu")
		(at 59.330336 -164.534596 -90)
		(property "Reference" "R1108"
			(at -1.509776 0.065532 90)
			(unlocked yes)
			(layer "F.SilkS")
			(effects
				(font
					(size 0.7874 0.5842)
					(thickness 0.1524)
				)
				(justify left)
			)
		)
		(property "Value" ""
			(at 0 0 270)
			(layer "F.Fab")
			(effects
				(font
					(size 1.27 1.27)
				)
			)
		)
		(duplicate_pad_numbers_are_jumpers no)
		(fp_line
			(start -0.7874 0.4064)
			(end -0.7874 -0.4064)
			(stroke
				(width 0.1524)
				(type default)
			)
			(layer "F.SilkS")
		)
		(fp_line
			(start 0.7874 0.4064)
			(end -0.7874 0.4064)
			(stroke
				(width 0.1524)
				(type default)
			)
			(layer "F.SilkS")
		)
		(fp_line
			(start -0.7874 -0.4064)
			(end 0.7874 -0.4064)
			(stroke
				(width 0.1524)
				(type default)
			)
			(layer "F.SilkS")
		)
		(fp_line
			(start 0.7874 -0.4064)
			(end 0.7874 0.4064)
			(stroke
				(width 0.1524)
				(type default)
			)
			(layer "F.SilkS")
		)
		(fp_poly
			(pts
				(xy -0.508 0.2794) (xy -0.508 0.2286) (xy -0.635 0.2286) (xy -0.635 -0.254) (xy -0.5334 -0.254)
				(xy -0.5334 -0.2794) (xy 0.5334 -0.2794) (xy 0.5334 -0.254) (xy 0.635 -0.254) (xy 0.635 0.254) (xy 0.5334 0.254)
				(xy 0.5334 0.2794)
			)
			(stroke
				(width 0)
				(type default)
			)
			(fill no)
			(layer "F.CrtYd")
		)
		(pad "1" smd rect
			(at 0.40005 0 270)
			(size 0.4572 0.508)
			(layers "F.Cu" "F.Mask" "F.Paste")
			(net "FM_CPLD_NODE1_P5V_EN")
		)
		(pad "2" smd rect
			(at -0.40005 0 270)
			(size 0.4572 0.508)
			(layers "F.Cu" "F.Mask" "F.Paste")
			(net "P3V3_STB_NODE1")
		)
	)
	(footprint ""
		(layer "F.Cu")
		(at 114.655854 -28.99791 -90)
		(property "Reference" "C857"
			(at -2.186432 -0.954532 90)
			(unlocked yes)
			(layer "F.SilkS")
			(effects
				(font
					(size 0.7874 0.5842)
					(thickness 0.1524)
				)
				(justify left)
			)
		)
		(property "Value" ""
			(at 0 0 270)
			(layer "F.Fab")
			(effects
				(font
					(size 1.27 1.27)
				)
			)
		)
		(duplicate_pad_numbers_are_jumpers no)
		(fp_line
			(start -1.905 0.8636)
			(end -1.905 -0.8636)
			(stroke
				(width 0.1524)
				(type default)
			)
			(layer "F.SilkS")
		)
		(fp_line
			(start 1.905 0.8636)
			(end -1.905 0.8636)
			(stroke
				(width 0.1524)
				(type default)
			)
			(layer "F.SilkS")
		)
		(fp_line
			(start 0 0.8382)
			(end 0 -0.8382)
			(stroke
				(width 0.1524)
				(type default)
			)
			(layer "F.SilkS")
		)
		(fp_line
			(start -1.905 -0.8636)
			(end 1.905 -0.8636)
			(stroke
				(width 0.1524)
				(type default)
			)
			(layer "F.SilkS")
		)
		(fp_line
			(start 1.905 -0.8636)
			(end 1.905 0.8636)
			(stroke
				(width 0.1524)
				(type default)
			)
			(layer "F.SilkS")
		)
		(fp_rect
			(start -1.524 0.7366)
			(end 1.524 -0.7366)
			(stroke
				(width 0)
				(type default)
			)
			(fill no)
			(layer "F.CrtYd")
		)
		(pad "1" smd rect
			(at 0.94996 0 270)
			(size 1.1176 1.3716)
			(layers "F.Cu" "F.Mask" "F.Paste")
			(net "PV_VTT_DDR_NODE1")
		)
		(pad "2" smd rect
			(at -0.94996 0 270)
			(size 1.1176 1.3716)
			(layers "F.Cu" "F.Mask" "F.Paste")
			(net "GND")
		)
	)
	(footprint ""
		(layer "F.Cu")
		(at 94.451932 -179.386992)
		(property "Reference" "R737"
			(at 86.67369 74.174096 0)
			(unlocked yes)
			(layer "F.SilkS")
			(effects
				(font
					(size 0.7874 0.5842)
					(thickness 0.1524)
				)
				(justify left)
			)
		)
		(property "Value" ""
			(at 0 0 0)
			(layer "F.Fab")
			(effects
				(font
					(size 1.27 1.27)
				)
			)
		)
		(duplicate_pad_numbers_are_jumpers no)
		(fp_line
			(start -0.7874 -0.4064)
			(end 0.7874 -0.4064)
			(stroke
				(width 0.1524)
				(type default)
			)
			(layer "F.SilkS")
		)
		(fp_line
			(start -0.7874 0.4064)
			(end -0.7874 -0.4064)
			(stroke
				(width 0.1524)
				(type default)
			)
			(layer "F.SilkS")
		)
		(fp_line
			(start 0.7874 -0.4064)
			(end 0.7874 0.4064)
			(stroke
				(width 0.1524)
				(type default)
			)
			(layer "F.SilkS")
		)
		(fp_line
			(start 0.7874 0.4064)
			(end -0.7874 0.4064)
			(stroke
				(width 0.1524)
				(type default)
			)
			(layer "F.SilkS")
		)
		(fp_poly
			(pts
				(xy -0.508 0.2794) (xy -0.508 0.2286) (xy -0.635 0.2286) (xy -0.635 -0.254) (xy -0.5334 -0.254)
				(xy -0.5334 -0.2794) (xy 0.5334 -0.2794) (xy 0.5334 -0.254) (xy 0.635 -0.254) (xy 0.635 0.254) (xy 0.5334 0.254)
				(xy 0.5334 0.2794)
			)
			(stroke
				(width 0)
				(type default)
			)
			(fill no)
			(layer "F.CrtYd")
		)
		(pad "1" smd rect
			(at 0.40005 0)
			(size 0.4572 0.508)
			(layers "F.Cu" "F.Mask" "F.Paste")
			(net "N21700941")
		)
		(pad "2" smd rect
			(at -0.40005 0)
			(size 0.4572 0.508)
			(layers "F.Cu" "F.Mask" "F.Paste")
			(net "P3V3_NODE1")
		)
	)
	(footprint ""
		(layer "F.Cu")
		(at 161.485072 -73.428606)
		(property "Reference" "C884"
			(at -6.732778 0.930656 0)
			(unlocked yes)
			(layer "F.SilkS")
			(effects
				(font
					(size 0.7874 0.5842)
					(thickness 0.1524)
				)
				(justify left)
			)
		)
		(property "Value" ""
			(at 0 0 0)
			(layer "F.Fab")
			(effects
				(font
					(size 1.27 1.27)
				)
			)
		)
		(duplicate_pad_numbers_are_jumpers no)
		(fp_line
			(start -0.7874 -0.4064)
			(end 0.7874 -0.4064)
			(stroke
				(width 0.1524)
				(type default)
			)
			(layer "F.SilkS")
		)
		(fp_line
			(start -0.7874 0.4064)
			(end -0.7874 -0.4064)
			(stroke
				(width 0.1524)
				(type default)
			)
			(layer "F.SilkS")
		)
		(fp_line
			(start 0 0.381)
			(end 0 -0.381)
			(stroke
				(width 0.1524)
				(type default)
			)
			(layer "F.SilkS")
		)
		(fp_line
			(start 0.7874 -0.4064)
			(end 0.7874 0.4064)
			(stroke
				(width 0.1524)
				(type default)
			)
			(layer "F.SilkS")
		)
		(fp_line
			(start 0.7874 0.4064)
			(end -0.7874 0.4064)
			(stroke
				(width 0.1524)
				(type default)
			)
			(layer "F.SilkS")
		)
		(fp_poly
			(pts
				(xy -0.5334 0.254) (xy -0.635 0.254) (xy -0.635 0.2286) (xy -0.635 -0.254) (xy -0.5334 -0.254) (xy -0.5334 -0.2794)
				(xy 0.5334 -0.2794) (xy 0.5334 -0.254) (xy 0.635 -0.254) (xy 0.635 0.254) (xy 0.5334 0.254) (xy 0.5334 0.2794)
				(xy -0.508 0.2794) (xy -0.5334 0.2794)
			)
			(stroke
				(width 0)
				(type default)
			)
			(fill no)
			(layer "F.CrtYd")
		)
		(pad "1" smd rect
			(at 0.40005 0)
			(size 0.4572 0.508)
			(layers "F.Cu" "F.Mask" "F.Paste")
			(net "GND")
		)
		(pad "2" smd rect
			(at -0.40005 0)
			(size 0.4572 0.508)
			(layers "F.Cu" "F.Mask" "F.Paste")
			(net "PWRGD_NODE1_P1V0")
		)
	)
)
